(kicad_pcb
	(version 20260206)
	(generator "pcbnew")
	(generator_version "10.0")
	(general
		(thickness 1.6)
		(legacy_teardrops no)
	)
	(paper "A4")
	(title_block
		(title "01162023_DA0F0TEBIF0_F0T_Expander_BD_F_brd_V02_OCP.brd")
		(comment 1 "Grand Teton / footprint 5622 of 9728 (PEX2), pads 1308-1423 of 2397")
	)
	(layers
		(0 "F.Cu" signal "TOP")
		(4 "In1.Cu" signal "GND")
		(6 "In2.Cu" signal "VCC")
		(8 "In3.Cu" signal "VCC1")
		(10 "In4.Cu" signal "GND1")
		(12 "In5.Cu" signal "IN1")
		(14 "In6.Cu" signal "GND2")
		(16 "In7.Cu" signal "IN2")
		(18 "In8.Cu" signal "GND3")
		(20 "In9.Cu" signal "IN3")
		(22 "In10.Cu" signal "GND4")
		(24 "In11.Cu" signal "IN4")
		(26 "In12.Cu" signal "GND5")
		(28 "In13.Cu" signal "IN5")
		(30 "In14.Cu" signal "GND6")
		(32 "In15.Cu" signal "IN6")
		(34 "In16.Cu" signal "GND7")
		(2 "B.Cu" signal "BOTTOM")
		(9 "F.Adhes" user "F.Adhesive")
		(11 "B.Adhes" user "B.Adhesive")
		(13 "F.Paste" user "Package Geometry/Pastemask Top")
		(15 "B.Paste" user "Package Geometry/Pastemask Bottom")
		(5 "F.SilkS" user "Ref Des/Silkscreen Top")
		(7 "B.SilkS" user "Ref Des/Silkscreen Bottom")
		(1 "F.Mask" user "Board Geometry/Soldermask Top")
		(3 "B.Mask" user "Board Geometry/Soldermask Bottom")
		(17 "Dwgs.User" user "User.Drawings")
		(19 "Cmts.User" user "User.Comments")
		(21 "Eco1.User" user "User.Eco1")
		(23 "Eco2.User" user "User.Eco2")
		(25 "Edge.Cuts" user "Board Geometry/Outline")
		(27 "Margin" user)
		(31 "F.CrtYd" user "Package Geometry/Place Bound Top")
		(29 "B.CrtYd" user "Package Geometry/Place Bound Bottom")
		(35 "F.Fab" user "Ref Des/Assembly Top")
		(33 "B.Fab" user "Ref Des/Assembly Bottom")
	)
	(footprint ""
		(layer "F.Cu")
		(at 291.84981 -295.89984)
		(property "Reference" "PEX2"
			(at -3.35153 35.56762 0)
			(unlocked yes)
			(layer "F.SilkS")
			(effects
				(font
					(size 2.032 1.524)
					(thickness 0.1524)
				)
				(justify left)
			)
		)
		(property "Value" ""
			(at 0 0 0)
			(layer "F.Fab")
			(effects
				(font
					(size 1.27 1.27)
				)
			)
		)
		(duplicate_pad_numbers_are_jumpers no)
		(pad "BE36" smd circle
			(at 10.450068 18.999962)
			(size 0.4572 0.4572)
			(layers "F.Cu" "F.Mask" "F.Paste")
			(net "GND")
		)
		(pad "BE37" smd circle
			(at 11.400028 18.999962)
			(size 0.4572 0.4572)
			(layers "F.Cu" "F.Mask" "F.Paste")
			(net "GND")
		)
		(pad "BE38" smd circle
			(at 12.349988 18.999962)
			(size 0.4572 0.4572)
			(layers "F.Cu" "F.Mask" "F.Paste")
			(net "GND")
		)
		(pad "BE39" smd circle
			(at 13.299948 18.999962)
			(size 0.4572 0.4572)
			(layers "F.Cu" "F.Mask" "F.Paste")
			(net "GND")
		)
		(pad "BE40" smd circle
			(at 14.249908 18.999962)
			(size 0.4572 0.4572)
			(layers "F.Cu" "F.Mask" "F.Paste")
			(net "GND")
		)
		(pad "BE41" smd circle
			(at 15.200122 18.999962)
			(size 0.4572 0.4572)
			(layers "F.Cu" "F.Mask" "F.Paste")
			(net "GND")
		)
		(pad "BE42" smd circle
			(at 16.150082 18.999962)
			(size 0.4572 0.4572)
			(layers "F.Cu" "F.Mask" "F.Paste")
			(net "GND")
		)
		(pad "BE43" smd circle
			(at 17.100042 18.999962)
			(size 0.4572 0.4572)
			(layers "F.Cu" "F.Mask" "F.Paste")
			(net "GND")
		)
		(pad "BE44" smd circle
			(at 18.050002 18.999962)
			(size 0.4572 0.4572)
			(layers "F.Cu" "F.Mask" "F.Paste")
			(net "GND")
		)
		(pad "BE45" smd circle
			(at 18.999962 18.999962)
			(size 0.4572 0.4572)
			(layers "F.Cu" "F.Mask" "F.Paste")
			(net "GND")
		)
		(pad "BE46" smd circle
			(at 19.949922 18.999962)
			(size 0.4572 0.4572)
			(layers "F.Cu" "F.Mask" "F.Paste")
			(net "GND")
		)
		(pad "BE47" smd circle
			(at 20.899882 18.999962)
			(size 0.4572 0.4572)
			(layers "F.Cu" "F.Mask" "F.Paste")
			(net "GND")
		)
		(pad "BE48" smd circle
			(at 21.850096 18.999962)
			(size 0.4572 0.4572)
			(layers "F.Cu" "F.Mask" "F.Paste")
			(net "P5E_PEX2_STN0_TX_DP<8>")
		)
		(pad "BE49" smd circle
			(at 22.800056 18.999962)
			(size 0.4572 0.4572)
			(layers "F.Cu" "F.Mask" "F.Paste")
			(net "P5E_PEX2_STN0_TX_DN<8>")
		)
		(pad "BF1" smd circle
			(at -22.800056 19.949922)
			(size 0.4572 0.4572)
			(layers "F.Cu" "F.Mask" "F.Paste")
			(net "GND")
		)
		(pad "BF2" smd circle
			(at -21.850096 19.949922)
			(size 0.4572 0.4572)
			(layers "F.Cu" "F.Mask" "F.Paste")
			(net "GND")
		)
		(pad "BF3" smd circle
			(at -20.899882 19.949922)
			(size 0.4572 0.4572)
			(layers "F.Cu" "F.Mask" "F.Paste")
			(net "GND")
		)
		(pad "BF4" smd circle
			(at -19.949922 19.949922)
			(size 0.4572 0.4572)
			(layers "F.Cu" "F.Mask" "F.Paste")
			(net "Net_1617")
		)
		(pad "BF5" smd circle
			(at -18.999962 19.949922)
			(size 0.4572 0.4572)
			(layers "F.Cu" "F.Mask" "F.Paste")
			(net "GND")
		)
		(pad "BF6" smd circle
			(at -18.050002 19.949922)
			(size 0.4572 0.4572)
			(layers "F.Cu" "F.Mask" "F.Paste")
			(net "Net_1552")
		)
		(pad "BF7" smd circle
			(at -17.100042 19.949922)
			(size 0.4572 0.4572)
			(layers "F.Cu" "F.Mask" "F.Paste")
			(net "GND")
		)
		(pad "BF8" smd circle
			(at -16.150082 19.949922)
			(size 0.4572 0.4572)
			(layers "F.Cu" "F.Mask" "F.Paste")
			(net "Net_1644")
		)
		(pad "BF9" smd circle
			(at -15.200122 19.949922)
			(size 0.4572 0.4572)
			(layers "F.Cu" "F.Mask" "F.Paste")
			(net "GND")
		)
		(pad "BF10" smd circle
			(at -14.249908 19.949922)
			(size 0.4572 0.4572)
			(layers "F.Cu" "F.Mask" "F.Paste")
			(net "P5E_PEX2_STN2_RX_DP<46>")
		)
		(pad "BF11" smd circle
			(at -13.299948 19.949922)
			(size 0.4572 0.4572)
			(layers "F.Cu" "F.Mask" "F.Paste")
			(net "GND")
		)
		(pad "BF12" smd circle
			(at -12.349988 19.949922)
			(size 0.4572 0.4572)
			(layers "F.Cu" "F.Mask" "F.Paste")
			(net "P5E_PEX2_STN2_RX_DP<44>")
		)
		(pad "BF13" smd circle
			(at -11.400028 19.949922)
			(size 0.4572 0.4572)
			(layers "F.Cu" "F.Mask" "F.Paste")
			(net "GND")
		)
		(pad "BF14" smd circle
			(at -10.450068 19.949922)
			(size 0.4572 0.4572)
			(layers "F.Cu" "F.Mask" "F.Paste")
			(net "P5E_PEX2_STN2_RX_DP<42>")
		)
		(pad "BF15" smd circle
			(at -9.500108 19.949922)
			(size 0.4572 0.4572)
			(layers "F.Cu" "F.Mask" "F.Paste")
			(net "GND")
		)
		(pad "BF16" smd circle
			(at -8.549894 19.949922)
			(size 0.4572 0.4572)
			(layers "F.Cu" "F.Mask" "F.Paste")
			(net "P5E_PEX2_STN2_RX_DP<40>")
		)
		(pad "BF17" smd circle
			(at -7.599934 19.949922)
			(size 0.4572 0.4572)
			(layers "F.Cu" "F.Mask" "F.Paste")
			(net "GND")
		)
		(pad "BF18" smd circle
			(at -6.649974 19.949922)
			(size 0.4572 0.4572)
			(layers "F.Cu" "F.Mask" "F.Paste")
			(net "P5E_PEX2_STN2_RX_DP<38>")
		)
		(pad "BF19" smd circle
			(at -5.700014 19.949922)
			(size 0.4572 0.4572)
			(layers "F.Cu" "F.Mask" "F.Paste")
			(net "GND")
		)
		(pad "BF20" smd circle
			(at -4.750054 19.949922)
			(size 0.4572 0.4572)
			(layers "F.Cu" "F.Mask" "F.Paste")
			(net "P5E_PEX2_STN2_RX_DP<36>")
		)
		(pad "BF21" smd circle
			(at -3.800094 19.949922)
			(size 0.4572 0.4572)
			(layers "F.Cu" "F.Mask" "F.Paste")
			(net "GND")
		)
		(pad "BF22" smd circle
			(at -2.84988 19.949922)
			(size 0.4572 0.4572)
			(layers "F.Cu" "F.Mask" "F.Paste")
			(net "P5E_PEX2_STN2_RX_DP<34>")
		)
		(pad "BF23" smd circle
			(at -1.89992 19.949922)
			(size 0.4572 0.4572)
			(layers "F.Cu" "F.Mask" "F.Paste")
			(net "GND")
		)
		(pad "BF24" smd circle
			(at -0.94996 19.949922)
			(size 0.4572 0.4572)
			(layers "F.Cu" "F.Mask" "F.Paste")
			(net "P5E_PEX2_STN2_RX_DP<32>")
		)
		(pad "BF25" smd circle
			(at 0 19.949922)
			(size 0.4572 0.4572)
			(layers "F.Cu" "F.Mask" "F.Paste")
			(net "GND")
		)
		(pad "BF26" smd circle
			(at 0.94996 19.949922)
			(size 0.4572 0.4572)
			(layers "F.Cu" "F.Mask" "F.Paste")
			(net "P5E_PEX2_STN1_RX_DP<17>")
		)
		(pad "BF27" smd circle
			(at 1.89992 19.949922)
			(size 0.4572 0.4572)
			(layers "F.Cu" "F.Mask" "F.Paste")
			(net "GND")
		)
		(pad "BF28" smd circle
			(at 2.84988 19.949922)
			(size 0.4572 0.4572)
			(layers "F.Cu" "F.Mask" "F.Paste")
			(net "P5E_PEX2_STN1_RX_DP<19>")
		)
		(pad "BF29" smd circle
			(at 3.800094 19.949922)
			(size 0.4572 0.4572)
			(layers "F.Cu" "F.Mask" "F.Paste")
			(net "GND")
		)
		(pad "BF30" smd circle
			(at 4.750054 19.949922)
			(size 0.4572 0.4572)
			(layers "F.Cu" "F.Mask" "F.Paste")
			(net "P5E_PEX2_STN1_RX_DP<21>")
		)
		(pad "BF31" smd circle
			(at 5.700014 19.949922)
			(size 0.4572 0.4572)
			(layers "F.Cu" "F.Mask" "F.Paste")
			(net "GND")
		)
		(pad "BF32" smd circle
			(at 6.649974 19.949922)
			(size 0.4572 0.4572)
			(layers "F.Cu" "F.Mask" "F.Paste")
			(net "P5E_PEX2_STN1_RX_DP<23>")
		)
		(pad "BF33" smd circle
			(at 7.599934 19.949922)
			(size 0.4572 0.4572)
			(layers "F.Cu" "F.Mask" "F.Paste")
			(net "GND")
		)
		(pad "BF34" smd circle
			(at 8.549894 19.949922)
			(size 0.4572 0.4572)
			(layers "F.Cu" "F.Mask" "F.Paste")
			(net "P5E_PEX2_STN1_RX_DP<25>")
		)
		(pad "BF35" smd circle
			(at 9.500108 19.949922)
			(size 0.4572 0.4572)
			(layers "F.Cu" "F.Mask" "F.Paste")
			(net "GND")
		)
		(pad "BF36" smd circle
			(at 10.450068 19.949922)
			(size 0.4572 0.4572)
			(layers "F.Cu" "F.Mask" "F.Paste")
			(net "P5E_PEX2_STN1_RX_DP<27>")
		)
		(pad "BF37" smd circle
			(at 11.400028 19.949922)
			(size 0.4572 0.4572)
			(layers "F.Cu" "F.Mask" "F.Paste")
			(net "GND")
		)
		(pad "BF38" smd circle
			(at 12.349988 19.949922)
			(size 0.4572 0.4572)
			(layers "F.Cu" "F.Mask" "F.Paste")
			(net "P5E_PEX2_STN1_RX_DP<29>")
		)
		(pad "BF39" smd circle
			(at 13.299948 19.949922)
			(size 0.4572 0.4572)
			(layers "F.Cu" "F.Mask" "F.Paste")
			(net "GND")
		)
		(pad "BF40" smd circle
			(at 14.249908 19.949922)
			(size 0.4572 0.4572)
			(layers "F.Cu" "F.Mask" "F.Paste")
			(net "P5E_PEX2_STN1_RX_DP<31>")
		)
		(pad "BF41" smd circle
			(at 15.200122 19.949922)
			(size 0.4572 0.4572)
			(layers "F.Cu" "F.Mask" "F.Paste")
			(net "GND")
		)
		(pad "BF42" smd circle
			(at 16.150082 19.949922)
			(size 0.4572 0.4572)
			(layers "F.Cu" "F.Mask" "F.Paste")
			(net "P5E_PEX2_STN0_RX_DP<14>")
		)
		(pad "BF43" smd circle
			(at 17.100042 19.949922)
			(size 0.4572 0.4572)
			(layers "F.Cu" "F.Mask" "F.Paste")
			(net "GND")
		)
		(pad "BF44" smd circle
			(at 18.050002 19.949922)
			(size 0.4572 0.4572)
			(layers "F.Cu" "F.Mask" "F.Paste")
			(net "P5E_PEX2_STN0_RX_DP<12>")
		)
		(pad "BF45" smd circle
			(at 18.999962 19.949922)
			(size 0.4572 0.4572)
			(layers "F.Cu" "F.Mask" "F.Paste")
			(net "GND")
		)
		(pad "BF46" smd circle
			(at 19.949922 19.949922)
			(size 0.4572 0.4572)
			(layers "F.Cu" "F.Mask" "F.Paste")
			(net "P5E_PEX2_STN0_RX_DP<10>")
		)
		(pad "BF47" smd circle
			(at 20.899882 19.949922)
			(size 0.4572 0.4572)
			(layers "F.Cu" "F.Mask" "F.Paste")
			(net "GND")
		)
		(pad "BF48" smd circle
			(at 21.850096 19.949922)
			(size 0.4572 0.4572)
			(layers "F.Cu" "F.Mask" "F.Paste")
			(net "GND")
		)
		(pad "BF49" smd circle
			(at 22.800056 19.949922)
			(size 0.4572 0.4572)
			(layers "F.Cu" "F.Mask" "F.Paste")
			(net "GND")
		)
		(pad "BG1" smd circle
			(at -22.800056 20.899882)
			(size 0.4572 0.4572)
			(layers "F.Cu" "F.Mask" "F.Paste")
			(net "Net_1542")
		)
		(pad "BG2" smd circle
			(at -21.850096 20.899882)
			(size 0.4572 0.4572)
			(layers "F.Cu" "F.Mask" "F.Paste")
			(net "Net_1576")
		)
		(pad "BG3" smd circle
			(at -20.899882 20.899882)
			(size 0.4572 0.4572)
			(layers "F.Cu" "F.Mask" "F.Paste")
			(net "GND")
		)
		(pad "BG4" smd circle
			(at -19.949922 20.899882)
			(size 0.4572 0.4572)
			(layers "F.Cu" "F.Mask" "F.Paste")
			(net "Net_1559")
		)
		(pad "BG5" smd circle
			(at -18.999962 20.899882)
			(size 0.4572 0.4572)
			(layers "F.Cu" "F.Mask" "F.Paste")
			(net "GND")
		)
		(pad "BG6" smd circle
			(at -18.050002 20.899882)
			(size 0.4572 0.4572)
			(layers "F.Cu" "F.Mask" "F.Paste")
			(net "Net_1545")
		)
		(pad "BG7" smd circle
			(at -17.100042 20.899882)
			(size 0.4572 0.4572)
			(layers "F.Cu" "F.Mask" "F.Paste")
			(net "GND")
		)
		(pad "BG8" smd circle
			(at -16.150082 20.899882)
			(size 0.4572 0.4572)
			(layers "F.Cu" "F.Mask" "F.Paste")
			(net "Net_1528")
		)
		(pad "BG9" smd circle
			(at -15.200122 20.899882)
			(size 0.4572 0.4572)
			(layers "F.Cu" "F.Mask" "F.Paste")
			(net "GND")
		)
		(pad "BG10" smd circle
			(at -14.249908 20.899882)
			(size 0.4572 0.4572)
			(layers "F.Cu" "F.Mask" "F.Paste")
			(net "P5E_PEX2_STN2_RX_DN<46>")
		)
		(pad "BG11" smd circle
			(at -13.299948 20.899882)
			(size 0.4572 0.4572)
			(layers "F.Cu" "F.Mask" "F.Paste")
			(net "GND")
		)
		(pad "BG12" smd circle
			(at -12.349988 20.899882)
			(size 0.4572 0.4572)
			(layers "F.Cu" "F.Mask" "F.Paste")
			(net "P5E_PEX2_STN2_RX_DN<44>")
		)
		(pad "BG13" smd circle
			(at -11.400028 20.899882)
			(size 0.4572 0.4572)
			(layers "F.Cu" "F.Mask" "F.Paste")
			(net "GND")
		)
		(pad "BG14" smd circle
			(at -10.450068 20.899882)
			(size 0.4572 0.4572)
			(layers "F.Cu" "F.Mask" "F.Paste")
			(net "P5E_PEX2_STN2_RX_DN<42>")
		)
		(pad "BG15" smd circle
			(at -9.500108 20.899882)
			(size 0.4572 0.4572)
			(layers "F.Cu" "F.Mask" "F.Paste")
			(net "GND")
		)
		(pad "BG16" smd circle
			(at -8.549894 20.899882)
			(size 0.4572 0.4572)
			(layers "F.Cu" "F.Mask" "F.Paste")
			(net "P5E_PEX2_STN2_RX_DN<40>")
		)
		(pad "BG17" smd circle
			(at -7.599934 20.899882)
			(size 0.4572 0.4572)
			(layers "F.Cu" "F.Mask" "F.Paste")
			(net "GND")
		)
		(pad "BG18" smd circle
			(at -6.649974 20.899882)
			(size 0.4572 0.4572)
			(layers "F.Cu" "F.Mask" "F.Paste")
			(net "P5E_PEX2_STN2_RX_DN<38>")
		)
		(pad "BG19" smd circle
			(at -5.700014 20.899882)
			(size 0.4572 0.4572)
			(layers "F.Cu" "F.Mask" "F.Paste")
			(net "GND")
		)
		(pad "BG20" smd circle
			(at -4.750054 20.899882)
			(size 0.4572 0.4572)
			(layers "F.Cu" "F.Mask" "F.Paste")
			(net "P5E_PEX2_STN2_RX_DN<36>")
		)
		(pad "BG21" smd circle
			(at -3.800094 20.899882)
			(size 0.4572 0.4572)
			(layers "F.Cu" "F.Mask" "F.Paste")
			(net "GND")
		)
		(pad "BG22" smd circle
			(at -2.84988 20.899882)
			(size 0.4572 0.4572)
			(layers "F.Cu" "F.Mask" "F.Paste")
			(net "P5E_PEX2_STN2_RX_DN<34>")
		)
		(pad "BG23" smd circle
			(at -1.89992 20.899882)
			(size 0.4572 0.4572)
			(layers "F.Cu" "F.Mask" "F.Paste")
			(net "GND")
		)
		(pad "BG24" smd circle
			(at -0.94996 20.899882)
			(size 0.4572 0.4572)
			(layers "F.Cu" "F.Mask" "F.Paste")
			(net "P5E_PEX2_STN2_RX_DN<32>")
		)
		(pad "BG25" smd circle
			(at 0 20.899882)
			(size 0.4572 0.4572)
			(layers "F.Cu" "F.Mask" "F.Paste")
			(net "GND")
		)
		(pad "BG26" smd circle
			(at 0.94996 20.899882)
			(size 0.4572 0.4572)
			(layers "F.Cu" "F.Mask" "F.Paste")
			(net "P5E_PEX2_STN1_RX_DN<17>")
		)
		(pad "BG27" smd circle
			(at 1.89992 20.899882)
			(size 0.4572 0.4572)
			(layers "F.Cu" "F.Mask" "F.Paste")
			(net "GND")
		)
		(pad "BG28" smd circle
			(at 2.84988 20.899882)
			(size 0.4572 0.4572)
			(layers "F.Cu" "F.Mask" "F.Paste")
			(net "P5E_PEX2_STN1_RX_DN<19>")
		)
		(pad "BG29" smd circle
			(at 3.800094 20.899882)
			(size 0.4572 0.4572)
			(layers "F.Cu" "F.Mask" "F.Paste")
			(net "GND")
		)
		(pad "BG30" smd circle
			(at 4.750054 20.899882)
			(size 0.4572 0.4572)
			(layers "F.Cu" "F.Mask" "F.Paste")
			(net "P5E_PEX2_STN1_RX_DN<21>")
		)
		(pad "BG31" smd circle
			(at 5.700014 20.899882)
			(size 0.4572 0.4572)
			(layers "F.Cu" "F.Mask" "F.Paste")
			(net "GND")
		)
		(pad "BG32" smd circle
			(at 6.649974 20.899882)
			(size 0.4572 0.4572)
			(layers "F.Cu" "F.Mask" "F.Paste")
			(net "P5E_PEX2_STN1_RX_DN<23>")
		)
		(pad "BG33" smd circle
			(at 7.599934 20.899882)
			(size 0.4572 0.4572)
			(layers "F.Cu" "F.Mask" "F.Paste")
			(net "GND")
		)
		(pad "BG34" smd circle
			(at 8.549894 20.899882)
			(size 0.4572 0.4572)
			(layers "F.Cu" "F.Mask" "F.Paste")
			(net "P5E_PEX2_STN1_RX_DN<25>")
		)
		(pad "BG35" smd circle
			(at 9.500108 20.899882)
			(size 0.4572 0.4572)
			(layers "F.Cu" "F.Mask" "F.Paste")
			(net "GND")
		)
		(pad "BG36" smd circle
			(at 10.450068 20.899882)
			(size 0.4572 0.4572)
			(layers "F.Cu" "F.Mask" "F.Paste")
			(net "P5E_PEX2_STN1_RX_DN<27>")
		)
		(pad "BG37" smd circle
			(at 11.400028 20.899882)
			(size 0.4572 0.4572)
			(layers "F.Cu" "F.Mask" "F.Paste")
			(net "GND")
		)
		(pad "BG38" smd circle
			(at 12.349988 20.899882)
			(size 0.4572 0.4572)
			(layers "F.Cu" "F.Mask" "F.Paste")
			(net "P5E_PEX2_STN1_RX_DN<29>")
		)
		(pad "BG39" smd circle
			(at 13.299948 20.899882)
			(size 0.4572 0.4572)
			(layers "F.Cu" "F.Mask" "F.Paste")
			(net "GND")
		)
		(pad "BG40" smd circle
			(at 14.249908 20.899882)
			(size 0.4572 0.4572)
			(layers "F.Cu" "F.Mask" "F.Paste")
			(net "P5E_PEX2_STN1_RX_DN<31>")
		)
		(pad "BG41" smd circle
			(at 15.200122 20.899882)
			(size 0.4572 0.4572)
			(layers "F.Cu" "F.Mask" "F.Paste")
			(net "GND")
		)
		(pad "BG42" smd circle
			(at 16.150082 20.899882)
			(size 0.4572 0.4572)
			(layers "F.Cu" "F.Mask" "F.Paste")
			(net "P5E_PEX2_STN0_RX_DN<14>")
		)
		(pad "BG43" smd circle
			(at 17.100042 20.899882)
			(size 0.4572 0.4572)
			(layers "F.Cu" "F.Mask" "F.Paste")
			(net "GND")
		)
		(pad "BG44" smd circle
			(at 18.050002 20.899882)
			(size 0.4572 0.4572)
			(layers "F.Cu" "F.Mask" "F.Paste")
			(net "P5E_PEX2_STN0_RX_DN<12>")
		)
		(pad "BG45" smd circle
			(at 18.999962 20.899882)
			(size 0.4572 0.4572)
			(layers "F.Cu" "F.Mask" "F.Paste")
			(net "GND")
		)
		(pad "BG46" smd circle
			(at 19.949922 20.899882)
			(size 0.4572 0.4572)
			(layers "F.Cu" "F.Mask" "F.Paste")
			(net "P5E_PEX2_STN0_RX_DN<10>")
		)
		(pad "BG47" smd circle
			(at 20.899882 20.899882)
			(size 0.4572 0.4572)
			(layers "F.Cu" "F.Mask" "F.Paste")
			(net "GND")
		)
		(pad "BG48" smd circle
			(at 21.850096 20.899882)
			(size 0.4572 0.4572)
			(layers "F.Cu" "F.Mask" "F.Paste")
			(net "P5E_PEX2_STN0_RX_DP<8>")
		)
		(pad "BG49" smd circle
			(at 22.800056 20.899882)
			(size 0.4572 0.4572)
			(layers "F.Cu" "F.Mask" "F.Paste")
			(net "P5E_PEX2_STN0_RX_DN<8>")
		)
		(pad "BH1" smd circle
			(at -22.800056 21.850096)
			(size 0.4572 0.4572)
			(layers "F.Cu" "F.Mask" "F.Paste")
			(net "GND")
		)
		(pad "BH2" smd circle
			(at -21.850096 21.850096)
			(size 0.4572 0.4572)
			(layers "F.Cu" "F.Mask" "F.Paste")
			(net "GND")
		)
		(pad "BH3" smd circle
			(at -20.899882 21.850096)
			(size 0.4572 0.4572)
			(layers "F.Cu" "F.Mask" "F.Paste")
			(net "Net_1608")
		)
		(pad "BH4" smd circle
			(at -19.949922 21.850096)
			(size 0.4572 0.4572)
			(layers "F.Cu" "F.Mask" "F.Paste")
			(net "GND")
		)
	)
)
